# T6G (Grand Teton) — schematic netlist excerpt (pin names and nets, part order shuffled) for the footprints in the layout excerpt that follows; sources: Cadence DE-HDL packaged netlist, KiCad conversion of 04192023_DAF0TMB3IC0_F0TG_MB_C_brd_V02_OCP.brd

R2898  Q_RES  33.2 1% CHIP  pkg 0402LF  page 248 : A = SMB_1_BMC_GPU_BUF_R_SDA ; B = SMB_1_BMC_GPU_BUF_SDA
C2551  Q_CAP  22UF 4V 20% X6S  pkg C0402  page 70 : A = PVDDCR_SOC_P0 ; B = GND

(kicad_pcb
	(version 20260206)
	(generator "pcbnew")
	(generator_version "10.0")
	(general
		(thickness 1.6)
		(legacy_teardrops no)
	)
	(paper "A4")
	(title_block
		(title "04192023_DAF0TMB3IC0_F0TG_MB_C_brd_V02_OCP.brd")
		(comment 1 "Grand Teton / footprints 2244-2245 of 8354")
	)
	(layers
		(0 "F.Cu" signal "TOP")
		(4 "In1.Cu" signal "GND")
		(6 "In2.Cu" signal "IN1")
		(8 "In3.Cu" signal "GND1")
		(10 "In4.Cu" signal "IN2")
		(12 "In5.Cu" signal "GND2")
		(14 "In6.Cu" signal "IN3")
		(16 "In7.Cu" signal "GND3")
		(18 "In8.Cu" signal "VCC")
		(20 "In9.Cu" signal "VCC1")
		(22 "In10.Cu" signal "GND4")
		(24 "In11.Cu" signal "IN4")
		(26 "In12.Cu" signal "GND5")
		(28 "In13.Cu" signal "IN5")
		(30 "In14.Cu" signal "GND6")
		(32 "In15.Cu" signal "IN6")
		(34 "In16.Cu" signal "GND7")
		(2 "B.Cu" signal "BOTTOM")
		(9 "F.Adhes" user "F.Adhesive")
		(11 "B.Adhes" user "B.Adhesive")
		(13 "F.Paste" user "Package Geometry/Pastemask Top")
		(15 "B.Paste" user "Package Geometry/Pastemask Bottom")
		(5 "F.SilkS" user "Ref Des/Silkscreen Top")
		(7 "B.SilkS" user "Ref Des/Silkscreen Bottom")
		(1 "F.Mask" user "Board Geometry/Soldermask Top")
		(3 "B.Mask" user "Board Geometry/Soldermask Bottom")
		(17 "Dwgs.User" user "User.Drawings")
		(19 "Cmts.User" user "User.Comments")
		(21 "Eco1.User" user "User.Eco1")
		(23 "Eco2.User" user "User.Eco2")
		(25 "Edge.Cuts" user "Board Geometry/Outline")
		(27 "Margin" user)
		(31 "F.CrtYd" user "Package Geometry/Place Bound Top")
		(29 "B.CrtYd" user "Package Geometry/Place Bound Bottom")
		(35 "F.Fab" user "Ref Des/Assembly Top")
		(33 "B.Fab" user "Ref Des/Assembly Bottom")
	)
	(footprint ""
		(layer "F.Cu")
		(at 365.835692 -256.505202 180)
		(property "Reference" "C2551"
			(at 0 0 180)
			(layer "F.SilkS")
			(hide yes)
			(effects
				(font
					(size 1.27 1.27)
				)
			)
		)
		(property "Value" ""
			(at 0 0 180)
			(layer "F.Fab")
			(effects
				(font
					(size 1.27 1.27)
				)
			)
		)
		(duplicate_pad_numbers_are_jumpers no)
		(fp_line
			(start 0.7874 0.4064)
			(end -0.7874 0.4064)
			(stroke
				(width 0.1524)
				(type default)
			)
			(layer "F.SilkS")
		)
		(fp_line
			(start 0.7874 -0.4064)
			(end 0.7874 0.4064)
			(stroke
				(width 0.1524)
				(type default)
			)
			(layer "F.SilkS")
		)
		(fp_line
			(start -0.7874 0.4064)
			(end -0.7874 -0.4064)
			(stroke
				(width 0.1524)
				(type default)
			)
			(layer "F.SilkS")
		)
		(fp_line
			(start -0.7874 -0.4064)
			(end 0.7874 -0.4064)
			(stroke
				(width 0.1524)
				(type default)
			)
			(layer "F.SilkS")
		)
		(fp_line
			(start 0.67945 0.3048)
			(end 0.120396 0.3048)
			(stroke
				(width 0.1)
				(type default)
			)
			(layer "F.Fab")
		)
		(fp_line
			(start 0.67945 -0.3048)
			(end 0.67945 0.3048)
			(stroke
				(width 0.1)
				(type default)
			)
			(layer "F.Fab")
		)
		(fp_line
			(start 0.12065 -0.2794)
			(end 0.12065 -0.3048)
			(stroke
				(width 0.1)
				(type default)
			)
			(layer "F.Fab")
		)
		(fp_line
			(start 0.12065 -0.3048)
			(end 0.67945 -0.3048)
			(stroke
				(width 0.1)
				(type default)
			)
			(layer "F.Fab")
		)
		(fp_line
			(start 0.120396 0.3048)
			(end 0.120396 0.2794)
			(stroke
				(width 0.1)
				(type default)
			)
			(layer "F.Fab")
		)
		(fp_line
			(start 0.120396 0.2794)
			(end -0.12065 0.2794)
			(stroke
				(width 0.1)
				(type default)
			)
			(layer "F.Fab")
		)
		(fp_line
			(start -0.12065 0.3048)
			(end -0.67945 0.3048)
			(stroke
				(width 0.1)
				(type default)
			)
			(layer "F.Fab")
		)
		(fp_line
			(start -0.12065 0.2794)
			(end -0.12065 0.3048)
			(stroke
				(width 0.1)
				(type default)
			)
			(layer "F.Fab")
		)
		(fp_line
			(start -0.12065 -0.2794)
			(end 0.12065 -0.2794)
			(stroke
				(width 0.1)
				(type default)
			)
			(layer "F.Fab")
		)
		(fp_line
			(start -0.12065 -0.305054)
			(end -0.12065 -0.2794)
			(stroke
				(width 0.1)
				(type default)
			)
			(layer "F.Fab")
		)
		(fp_line
			(start -0.67945 0.3048)
			(end -0.67945 -0.305054)
			(stroke
				(width 0.1)
				(type default)
			)
			(layer "F.Fab")
		)
		(fp_line
			(start -0.67945 -0.305054)
			(end -0.12065 -0.305054)
			(stroke
				(width 0.1)
				(type default)
			)
			(layer "F.Fab")
		)
		(pad "1" smd circle
			(at -0.40005 0 180)
			(size 0 0)
			(layers "F.Cu" "F.Mask" "F.Paste")
			(net "PVDDCR_SOC_P0")
		)
		(pad "2" smd circle
			(at 0.40005 0 180)
			(size 0 0)
			(layers "F.Cu" "F.Mask" "F.Paste")
			(net "GND")
		)
	)
	(footprint ""
		(layer "F.Cu")
		(at 35.132772 -434.128164)
		(property "Reference" "R2898"
			(at 0 0 0)
			(layer "F.SilkS")
			(hide yes)
			(effects
				(font
					(size 1.27 1.27)
				)
			)
		)
		(property "Value" ""
			(at 0 0 0)
			(layer "F.Fab")
			(effects
				(font
					(size 1.27 1.27)
				)
			)
		)
		(duplicate_pad_numbers_are_jumpers no)
		(fp_line
			(start -0.7874 -0.4064)
			(end 0.7874 -0.4064)
			(stroke
				(width 0.1524)
				(type default)
			)
			(layer "F.SilkS")
		)
		(fp_line
			(start -0.7874 0.4064)
			(end -0.7874 -0.4064)
			(stroke
				(width 0.1524)
				(type default)
			)
			(layer "F.SilkS")
		)
		(fp_line
			(start 0.7874 -0.4064)
			(end 0.7874 0.4064)
			(stroke
				(width 0.1524)
				(type default)
			)
			(layer "F.SilkS")
		)
		(fp_line
			(start 0.7874 0.4064)
			(end -0.7874 0.4064)
			(stroke
				(width 0.1524)
				(type default)
			)
			(layer "F.SilkS")
		)
		(fp_line
			(start -0.67945 -0.305054)
			(end -0.12065 -0.305054)
			(stroke
				(width 0.1)
				(type default)
			)
			(layer "F.Fab")
		)
		(fp_line
			(start -0.67945 0.3048)
			(end -0.67945 -0.305054)
			(stroke
				(width 0.1)
				(type default)
			)
			(layer "F.Fab")
		)
		(fp_line
			(start -0.12065 -0.305054)
			(end -0.12065 -0.2794)
			(stroke
				(width 0.1)
				(type default)
			)
			(layer "F.Fab")
		)
		(fp_line
			(start -0.12065 -0.2794)
			(end 0.12065 -0.2794)
			(stroke
				(width 0.1)
				(type default)
			)
			(layer "F.Fab")
		)
		(fp_line
			(start -0.12065 0.2794)
			(end -0.12065 0.3048)
			(stroke
				(width 0.1)
				(type default)
			)
			(layer "F.Fab")
		)
		(fp_line
			(start -0.12065 0.3048)
			(end -0.67945 0.3048)
			(stroke
				(width 0.1)
				(type default)
			)
			(layer "F.Fab")
		)
		(fp_line
			(start 0.120396 0.2794)
			(end -0.12065 0.2794)
			(stroke
				(width 0.1)
				(type default)
			)
			(layer "F.Fab")
		)
		(fp_line
			(start 0.120396 0.3048)
			(end 0.120396 0.2794)
			(stroke
				(width 0.1)
				(type default)
			)
			(layer "F.Fab")
		)
		(fp_line
			(start 0.12065 -0.3048)
			(end 0.67945 -0.3048)
			(stroke
				(width 0.1)
				(type default)
			)
			(layer "F.Fab")
		)
		(fp_line
			(start 0.12065 -0.2794)
			(end 0.12065 -0.3048)
			(stroke
				(width 0.1)
				(type default)
			)
			(layer "F.Fab")
		)
		(fp_line
			(start 0.67945 -0.3048)
			(end 0.67945 0.3048)
			(stroke
				(width 0.1)
				(type default)
			)
			(layer "F.Fab")
		)
		(fp_line
			(start 0.67945 0.3048)
			(end 0.120396 0.3048)
			(stroke
				(width 0.1)
				(type default)
			)
			(layer "F.Fab")
		)
		(pad "1" smd circle
			(at -0.40005 0)
			(size 0 0)
			(layers "F.Cu" "F.Mask" "F.Paste")
			(net "SMB_1_BMC_GPU_BUF_R_SDA")
		)
		(pad "2" smd circle
			(at 0.40005 0)
			(size 0 0)
			(layers "F.Cu" "F.Mask" "F.Paste")
			(net "SMB_1_BMC_GPU_BUF_SDA")
		)
	)
)
